(kicad_pcb
	(version 20241229)
	(generator "pcbnew")
	(generator_version "9.0")
	(general
		(thickness 1.599998)
		(legacy_teardrops no)
	)
	(paper "A4")
	(title_block
		(title "Artix - Datacenter Secure Control Module (DC-SCM)")
		(date "2024-11-06")
		(rev "1.1.3")
		(comment 9 "footprint 256 of 544 (U19), pads 1-74 of 74")
	)
	(layers
		(0 "F.Cu" signal)
		(4 "In1.Cu" signal)
		(6 "In2.Cu" signal)
		(8 "In3.Cu" signal)
		(10 "In4.Cu" signal)
		(12 "In5.Cu" signal)
		(14 "In6.Cu" signal)
		(2 "B.Cu" signal)
		(9 "F.Adhes" user "F.Adhesive")
		(11 "B.Adhes" user "B.Adhesive")
		(13 "F.Paste" user)
		(15 "B.Paste" user)
		(5 "F.SilkS" user "F.Silkscreen")
		(7 "B.SilkS" user "B.Silkscreen")
		(1 "F.Mask" user)
		(3 "B.Mask" user)
		(17 "Dwgs.User" user "User.Drawings")
		(19 "Cmts.User" user "User.Comments")
		(21 "Eco1.User" user "User.Eco1")
		(23 "Eco2.User" user "User.Eco2")
		(25 "Edge.Cuts" user)
		(27 "Margin" user)
		(31 "F.CrtYd" user "F.Courtyard")
		(29 "B.CrtYd" user "B.Courtyard")
		(35 "F.Fab" user)
		(33 "B.Fab" user)
	)
	(footprint "antmicro-footprints:QFN-64-1EP_9x9mm_P0.5mm"
		(layer "F.Cu")
		(at 134.6 95.3 -90)
		(property "Reference" "U19"
			(at 5.075 4.925 0)
			(layer "F.SilkS")
			(effects
				(font
					(size 0.7 0.7)
					(thickness 0.15)
				)
				(justify left top)
			)
		)
		(property "Value" "FT4232H_QFN"
			(at 0 5.9 90)
			(layer "F.Fab")
			(effects
				(font
					(size 0.7 0.7)
					(thickness 0.15)
				)
				(justify right bottom)
			)
		)
		(property "Datasheet" "https://www.ftdichip.com/Support/Documents/DataSheets/ICs/DS_FT4232H.pdf"
			(at 0 0 90)
			(layer "F.Fab")
			(hide yes)
			(effects
				(font
					(size 1.27 1.27)
					(thickness 0.15)
				)
			)
		)
		(property "Description" "Interface Bridges, USB to UART, MPSSE, 1.62 V, 1.98 V, QFN, 64 Pins, -40 °C"
			(at 0 0 90)
			(layer "F.Fab")
			(hide yes)
			(effects
				(font
					(size 1.27 1.27)
					(thickness 0.15)
				)
			)
		)
		(property "Author" "Antmicro"
			(at 39.3 229.9 0)
			(layer "F.Fab")
			(hide yes)
			(effects
				(font
					(size 1 1)
					(thickness 0.15)
				)
			)
		)
		(property "License" "Apache-2.0"
			(at 39.3 229.9 0)
			(layer "F.Fab")
			(hide yes)
			(effects
				(font
					(size 1 1)
					(thickness 0.15)
				)
			)
		)
		(property "MPN" "FT4232HQ-TRAY"
			(at 39.3 229.9 0)
			(layer "F.Fab")
			(hide yes)
			(effects
				(font
					(size 1 1)
					(thickness 0.15)
				)
			)
		)
		(property "Manufacturer" "FTDI Chip"
			(at 39.3 229.9 0)
			(layer "F.Fab")
			(hide yes)
			(effects
				(font
					(size 1 1)
					(thickness 0.15)
				)
			)
		)
		(sheetname "/Interfaces/")
		(sheetfile "interfaces.kicad_sch")
		(attr smd)
		(pad "" smd roundrect
			(at -1.401 -1.401 270)
			(size 1.05 1.05)
			(layers "F.Paste")
			(roundrect_rratio 0.197928)
		)
		(pad "" smd roundrect
			(at -1.401 0 270)
			(size 1.05 1.05)
			(layers "F.Paste")
			(roundrect_rratio 0.197928)
		)
		(pad "" smd roundrect
			(at -1.401 1.398 270)
			(size 1.05 1.05)
			(layers "F.Paste")
			(roundrect_rratio 0.197928)
		)
		(pad "" smd roundrect
			(at 0 -1.401 270)
			(size 1.05 1.05)
			(layers "F.Paste")
			(roundrect_rratio 0.197928)
		)
		(pad "" smd roundrect
			(at 0 0 270)
			(size 1.05 1.05)
			(layers "F.Paste")
			(roundrect_rratio 0.197928)
		)
		(pad "" smd roundrect
			(at 0 1.398 270)
			(size 1.05 1.05)
			(layers "F.Paste")
			(roundrect_rratio 0.197928)
		)
		(pad "" smd roundrect
			(at 1.398 -1.401 270)
			(size 1.05 1.05)
			(layers "F.Paste")
			(roundrect_rratio 0.197928)
		)
		(pad "" smd roundrect
			(at 1.398 0 270)
			(size 1.05 1.05)
			(layers "F.Paste")
			(roundrect_rratio 0.197928)
		)
		(pad "" smd roundrect
			(at 1.398 1.398 270)
			(size 1.05 1.05)
			(layers "F.Paste")
			(roundrect_rratio 0.197928)
		)
		(pad "1" smd roundrect
			(at -4.414 -3.75 270)
			(size 0.875 0.2)
			(layers "F.Cu" "F.Mask" "F.Paste")
			(roundrect_rratio 0.25)
			(net 1 "GND")
			(pinfunction "GND")
			(pintype "power_in")
		)
		(pad "2" smd roundrect
			(at -4.414 -3.25 270)
			(size 0.875 0.2)
			(layers "F.Cu" "F.Mask" "F.Paste")
			(roundrect_rratio 0.25)
			(net 197 "Net-(U19-OSCI)")
			(pinfunction "OSCI")
			(pintype "input")
		)
		(pad "3" smd roundrect
			(at -4.414 -2.75 270)
			(size 0.875 0.2)
			(layers "F.Cu" "F.Mask" "F.Paste")
			(roundrect_rratio 0.25)
			(net 198 "Net-(U19-OSCO)")
			(pinfunction "OSCO")
			(pintype "output")
		)
		(pad "4" smd roundrect
			(at -4.414 -2.25 270)
			(size 0.875 0.2)
			(layers "F.Cu" "F.Mask" "F.Paste")
			(roundrect_rratio 0.25)
			(net 115 "/Interfaces/FT_VPHY")
			(pinfunction "V_{PHY}")
			(pintype "power_in")
		)
		(pad "5" smd roundrect
			(at -4.414 -1.75 270)
			(size 0.875 0.2)
			(layers "F.Cu" "F.Mask" "F.Paste")
			(roundrect_rratio 0.25)
			(net 1 "GND")
			(pinfunction "GND")
			(pintype "passive")
		)
		(pad "6" smd roundrect
			(at -4.414 -1.25 270)
			(size 0.875 0.2)
			(layers "F.Cu" "F.Mask" "F.Paste")
			(roundrect_rratio 0.25)
			(net 298 "Net-(U19-REF)")
			(pinfunction "REF")
			(pintype "input")
		)
		(pad "7" smd roundrect
			(at -4.414 -0.75 270)
			(size 0.875 0.2)
			(layers "F.Cu" "F.Mask" "F.Paste")
			(roundrect_rratio 0.25)
			(net 213 "/Interfaces/DBG_USB_D_N")
			(pinfunction "D-")
			(pintype "bidirectional")
		)
		(pad "8" smd roundrect
			(at -4.414 -0.25 270)
			(size 0.875 0.2)
			(layers "F.Cu" "F.Mask" "F.Paste")
			(roundrect_rratio 0.25)
			(net 212 "/Interfaces/DBG_USB_D_P")
			(pinfunction "D+")
			(pintype "bidirectional")
		)
		(pad "9" smd roundrect
			(at -4.414 0.248 270)
			(size 0.875 0.2)
			(layers "F.Cu" "F.Mask" "F.Paste")
			(roundrect_rratio 0.25)
			(net 116 "/Interfaces/FT_VPLL")
			(pinfunction "V_{PLL}")
			(pintype "power_in")
		)
		(pad "10" smd roundrect
			(at -4.414 0.748 270)
			(size 0.875 0.2)
			(layers "F.Cu" "F.Mask" "F.Paste")
			(roundrect_rratio 0.25)
			(net 1 "GND")
			(pinfunction "AGND")
			(pintype "power_in")
		)
		(pad "11" smd roundrect
			(at -4.414 1.249 270)
			(size 0.875 0.2)
			(layers "F.Cu" "F.Mask" "F.Paste")
			(roundrect_rratio 0.25)
			(net 1 "GND")
			(pinfunction "GND")
			(pintype "passive")
		)
		(pad "12" smd roundrect
			(at -4.414 1.749 270)
			(size 0.875 0.2)
			(layers "F.Cu" "F.Mask" "F.Paste")
			(roundrect_rratio 0.25)
			(net 597 "1V8_FT")
			(pinfunction "V_{CORE}")
			(pintype "power_in")
		)
		(pad "13" smd roundrect
			(at -4.414 2.249 270)
			(size 0.875 0.2)
			(layers "F.Cu" "F.Mask" "F.Paste")
			(roundrect_rratio 0.25)
			(net 1 "GND")
			(pinfunction "TEST")
			(pintype "input")
		)
		(pad "14" smd roundrect
			(at -4.414 2.749 270)
			(size 0.875 0.2)
			(layers "F.Cu" "F.Mask" "F.Paste")
			(roundrect_rratio 0.25)
			(net 299 "Net-(U19-~{RESET})")
			(pinfunction "~{RESET}")
			(pintype "input")
		)
		(pad "15" smd roundrect
			(at -4.414 3.249 270)
			(size 0.875 0.2)
			(layers "F.Cu" "F.Mask" "F.Paste")
			(roundrect_rratio 0.25)
			(net 1 "GND")
			(pinfunction "GND")
			(pintype "passive")
		)
		(pad "16" smd roundrect
			(at -4.414 3.749 270)
			(size 0.875 0.2)
			(layers "F.Cu" "F.Mask" "F.Paste")
			(roundrect_rratio 0.25)
			(net 346 "Net-(U19-ADBUS0)")
			(pinfunction "ADBUS0")
			(pintype "bidirectional")
		)
		(pad "17" smd roundrect
			(at -3.75 4.411 270)
			(size 0.2 0.875)
			(layers "F.Cu" "F.Mask" "F.Paste")
			(roundrect_rratio 0.25)
			(net 348 "Net-(U19-ADBUS1)")
			(pinfunction "ADBUS1")
			(pintype "bidirectional")
		)
		(pad "18" smd roundrect
			(at -3.25 4.411 270)
			(size 0.2 0.875)
			(layers "F.Cu" "F.Mask" "F.Paste")
			(roundrect_rratio 0.25)
			(net 349 "Net-(U19-ADBUS2)")
			(pinfunction "ADBUS2")
			(pintype "bidirectional")
		)
		(pad "19" smd roundrect
			(at -2.75 4.411 270)
			(size 0.2 0.875)
			(layers "F.Cu" "F.Mask" "F.Paste")
			(roundrect_rratio 0.25)
			(net 399 "Net-(U19-ADBUS3)")
			(pinfunction "ADBUS3")
			(pintype "bidirectional")
		)
		(pad "20" smd roundrect
			(at -2.25 4.411 270)
			(size 0.2 0.875)
			(layers "F.Cu" "F.Mask" "F.Paste")
			(roundrect_rratio 0.25)
			(net 2 "VCC3V3")
			(pinfunction "V_{CCIO}")
			(pintype "power_in")
		)
		(pad "21" smd roundrect
			(at -1.75 4.411 270)
			(size 0.2 0.875)
			(layers "F.Cu" "F.Mask" "F.Paste")
			(roundrect_rratio 0.25)
			(net 657 "unconnected-(U19-ADBUS4-Pad21)")
			(pinfunction "ADBUS4")
			(pintype "bidirectional+no_connect")
		)
		(pad "22" smd roundrect
			(at -1.25 4.411 270)
			(size 0.2 0.875)
			(layers "F.Cu" "F.Mask" "F.Paste")
			(roundrect_rratio 0.25)
			(net 403 "Net-(U19-ADBUS5)")
			(pinfunction "ADBUS5")
			(pintype "bidirectional")
		)
		(pad "23" smd roundrect
			(at -0.75 4.411 270)
			(size 0.2 0.875)
			(layers "F.Cu" "F.Mask" "F.Paste")
			(roundrect_rratio 0.25)
			(net 658 "unconnected-(U19-ADBUS6-Pad23)")
			(pinfunction "ADBUS6")
			(pintype "bidirectional+no_connect")
		)
		(pad "24" smd roundrect
			(at -0.25 4.411 270)
			(size 0.2 0.875)
			(layers "F.Cu" "F.Mask" "F.Paste")
			(roundrect_rratio 0.25)
			(net 659 "unconnected-(U19-ADBUS7-Pad24)")
			(pinfunction "ADBUS7")
			(pintype "bidirectional+no_connect")
		)
		(pad "25" smd roundrect
			(at 0.248 4.411 270)
			(size 0.2 0.875)
			(layers "F.Cu" "F.Mask" "F.Paste")
			(roundrect_rratio 0.25)
			(net 1 "GND")
			(pinfunction "GND")
			(pintype "passive")
		)
		(pad "26" smd roundrect
			(at 0.748 4.411 270)
			(size 0.2 0.875)
			(layers "F.Cu" "F.Mask" "F.Paste")
			(roundrect_rratio 0.25)
			(net 660 "unconnected-(U19-BDBUS0-Pad26)")
			(pinfunction "BDBUS0")
			(pintype "bidirectional+no_connect")
		)
		(pad "27" smd roundrect
			(at 1.249 4.411 270)
			(size 0.2 0.875)
			(layers "F.Cu" "F.Mask" "F.Paste")
			(roundrect_rratio 0.25)
			(net 661 "unconnected-(U19-BDBUS1-Pad27)")
			(pinfunction "BDBUS1")
			(pintype "bidirectional+no_connect")
		)
		(pad "28" smd roundrect
			(at 1.749 4.411 270)
			(size 0.2 0.875)
			(layers "F.Cu" "F.Mask" "F.Paste")
			(roundrect_rratio 0.25)
			(net 662 "unconnected-(U19-BDBUS2-Pad28)")
			(pinfunction "BDBUS2")
			(pintype "bidirectional+no_connect")
		)
		(pad "29" smd roundrect
			(at 2.249 4.411 270)
			(size 0.2 0.875)
			(layers "F.Cu" "F.Mask" "F.Paste")
			(roundrect_rratio 0.25)
			(net 663 "unconnected-(U19-BDBUS3-Pad29)")
			(pinfunction "BDBUS3")
			(pintype "bidirectional+no_connect")
		)
		(pad "30" smd roundrect
			(at 2.749 4.411 270)
			(size 0.2 0.875)
			(layers "F.Cu" "F.Mask" "F.Paste")
			(roundrect_rratio 0.25)
			(net 664 "unconnected-(U19-BDBUS4-Pad30)")
			(pinfunction "BDBUS4")
			(pintype "bidirectional+no_connect")
		)
		(pad "31" smd roundrect
			(at 3.249 4.411 270)
			(size 0.2 0.875)
			(layers "F.Cu" "F.Mask" "F.Paste")
			(roundrect_rratio 0.25)
			(net 2 "VCC3V3")
			(pinfunction "V_{CCIO}")
			(pintype "passive")
		)
		(pad "32" smd roundrect
			(at 3.749 4.411 270)
			(size 0.2 0.875)
			(layers "F.Cu" "F.Mask" "F.Paste")
			(roundrect_rratio 0.25)
			(net 665 "unconnected-(U19-BDBUS5-Pad32)")
			(pinfunction "BDBUS5")
			(pintype "bidirectional+no_connect")
		)
		(pad "33" smd roundrect
			(at 4.411 3.749 270)
			(size 0.875 0.2)
			(layers "F.Cu" "F.Mask" "F.Paste")
			(roundrect_rratio 0.25)
			(net 666 "unconnected-(U19-BDBUS6-Pad33)")
			(pinfunction "BDBUS6")
			(pintype "bidirectional+no_connect")
		)
		(pad "34" smd roundrect
			(at 4.411 3.249 270)
			(size 0.875 0.2)
			(layers "F.Cu" "F.Mask" "F.Paste")
			(roundrect_rratio 0.25)
			(net 667 "unconnected-(U19-BDBUS7-Pad34)")
			(pinfunction "BDBUS7")
			(pintype "bidirectional+no_connect")
		)
		(pad "35" smd roundrect
			(at 4.411 2.749 270)
			(size 0.875 0.2)
			(layers "F.Cu" "F.Mask" "F.Paste")
			(roundrect_rratio 0.25)
			(net 1 "GND")
			(pinfunction "GND")
			(pintype "passive")
		)
		(pad "36" smd roundrect
			(at 4.411 2.249 270)
			(size 0.875 0.2)
			(layers "F.Cu" "F.Mask" "F.Paste")
			(roundrect_rratio 0.25)
			(net 668 "unconnected-(U19-SUSPEND-Pad36)")
			(pinfunction "SUSPEND")
			(pintype "output+no_connect")
		)
		(pad "37" smd roundrect
			(at 4.411 1.749 270)
			(size 0.875 0.2)
			(layers "F.Cu" "F.Mask" "F.Paste")
			(roundrect_rratio 0.25)
			(net 597 "1V8_FT")
			(pinfunction "V_{CORE}")
			(pintype "passive")
		)
		(pad "38" smd roundrect
			(at 4.411 1.249 270)
			(size 0.875 0.2)
			(layers "F.Cu" "F.Mask" "F.Paste")
			(roundrect_rratio 0.25)
			(net 400 "Net-(U19-CDBUS0)")
			(pinfunction "CDBUS0")
			(pintype "bidirectional")
		)
		(pad "39" smd roundrect
			(at 4.411 0.748 270)
			(size 0.875 0.2)
			(layers "F.Cu" "F.Mask" "F.Paste")
			(roundrect_rratio 0.25)
			(net 401 "Net-(U19-CDBUS1)")
			(pinfunction "CDBUS1")
			(pintype "bidirectional")
		)
		(pad "40" smd roundrect
			(at 4.411 0.248 270)
			(size 0.875 0.2)
			(layers "F.Cu" "F.Mask" "F.Paste")
			(roundrect_rratio 0.25)
			(net 669 "unconnected-(U19-CDBUS2-Pad40)")
			(pinfunction "CDBUS2")
			(pintype "bidirectional+no_connect")
		)
		(pad "41" smd roundrect
			(at 4.411 -0.25 270)
			(size 0.875 0.2)
			(layers "F.Cu" "F.Mask" "F.Paste")
			(roundrect_rratio 0.25)
			(net 670 "unconnected-(U19-CDBUS3-Pad41)")
			(pinfunction "CDBUS3")
			(pintype "bidirectional+no_connect")
		)
		(pad "42" smd roundrect
			(at 4.411 -0.75 270)
			(size 0.875 0.2)
			(layers "F.Cu" "F.Mask" "F.Paste")
			(roundrect_rratio 0.25)
			(net 2 "VCC3V3")
			(pinfunction "V_{CCIO}")
			(pintype "passive")
		)
		(pad "43" smd roundrect
			(at 4.411 -1.25 270)
			(size 0.875 0.2)
			(layers "F.Cu" "F.Mask" "F.Paste")
			(roundrect_rratio 0.25)
			(net 671 "unconnected-(U19-CDBUS4-Pad43)")
			(pinfunction "CDBUS4")
			(pintype "bidirectional+no_connect")
		)
		(pad "44" smd roundrect
			(at 4.411 -1.75 270)
			(size 0.875 0.2)
			(layers "F.Cu" "F.Mask" "F.Paste")
			(roundrect_rratio 0.25)
			(net 672 "unconnected-(U19-CDBUS5-Pad44)")
			(pinfunction "CDBUS5")
			(pintype "bidirectional+no_connect")
		)
		(pad "45" smd roundrect
			(at 4.411 -2.25 270)
			(size 0.875 0.2)
			(layers "F.Cu" "F.Mask" "F.Paste")
			(roundrect_rratio 0.25)
			(net 673 "unconnected-(U19-CDBUS6-Pad45)")
			(pinfunction "CDBUS6")
			(pintype "bidirectional+no_connect")
		)
		(pad "46" smd roundrect
			(at 4.411 -2.75 270)
			(size 0.875 0.2)
			(layers "F.Cu" "F.Mask" "F.Paste")
			(roundrect_rratio 0.25)
			(net 674 "unconnected-(U19-CDBUS7-Pad46)")
			(pinfunction "CDBUS7")
			(pintype "bidirectional+no_connect")
		)
		(pad "47" smd roundrect
			(at 4.411 -3.25 270)
			(size 0.875 0.2)
			(layers "F.Cu" "F.Mask" "F.Paste")
			(roundrect_rratio 0.25)
			(net 1 "GND")
			(pinfunction "GND")
			(pintype "passive")
		)
		(pad "48" smd roundrect
			(at 4.411 -3.75 270)
			(size 0.875 0.2)
			(layers "F.Cu" "F.Mask" "F.Paste")
			(roundrect_rratio 0.25)
			(net 675 "unconnected-(U19-DDBUS0-Pad48)")
			(pinfunction "DDBUS0")
			(pintype "bidirectional+no_connect")
		)
		(pad "49" smd roundrect
			(at 3.749 -4.414 270)
			(size 0.2 0.875)
			(layers "F.Cu" "F.Mask" "F.Paste")
			(roundrect_rratio 0.25)
			(net 597 "1V8_FT")
			(pinfunction "V_{REGOUT}")
			(pintype "power_out")
		)
		(pad "50" smd roundrect
			(at 3.249 -4.414 270)
			(size 0.2 0.875)
			(layers "F.Cu" "F.Mask" "F.Paste")
			(roundrect_rratio 0.25)
			(net 2 "VCC3V3")
			(pinfunction "V_{REGIN}")
			(pintype "power_in")
		)
		(pad "51" smd roundrect
			(at 2.749 -4.414 270)
			(size 0.2 0.875)
			(layers "F.Cu" "F.Mask" "F.Paste")
			(roundrect_rratio 0.25)
			(net 1 "GND")
			(pinfunction "GND")
			(pintype "passive")
		)
		(pad "52" smd roundrect
			(at 2.249 -4.414 270)
			(size 0.2 0.875)
			(layers "F.Cu" "F.Mask" "F.Paste")
			(roundrect_rratio 0.25)
			(net 676 "unconnected-(U19-DDBUS1-Pad52)")
			(pinfunction "DDBUS1")
			(pintype "bidirectional+no_connect")
		)
		(pad "53" smd roundrect
			(at 1.749 -4.414 270)
			(size 0.2 0.875)
			(layers "F.Cu" "F.Mask" "F.Paste")
			(roundrect_rratio 0.25)
			(net 677 "unconnected-(U19-DDBUS2-Pad53)")
			(pinfunction "DDBUS2")
			(pintype "bidirectional+no_connect")
		)
		(pad "54" smd roundrect
			(at 1.249 -4.414 270)
			(size 0.2 0.875)
			(layers "F.Cu" "F.Mask" "F.Paste")
			(roundrect_rratio 0.25)
			(net 678 "unconnected-(U19-DDBUS3-Pad54)")
			(pinfunction "DDBUS3")
			(pintype "bidirectional+no_connect")
		)
		(pad "55" smd roundrect
			(at 0.748 -4.414 270)
			(size 0.2 0.875)
			(layers "F.Cu" "F.Mask" "F.Paste")
			(roundrect_rratio 0.25)
			(net 679 "unconnected-(U19-DDBUS4-Pad55)")
			(pinfunction "DDBUS4")
			(pintype "bidirectional+no_connect")
		)
		(pad "56" smd roundrect
			(at 0.248 -4.414 270)
			(size 0.2 0.875)
			(layers "F.Cu" "F.Mask" "F.Paste")
			(roundrect_rratio 0.25)
			(net 2 "VCC3V3")
			(pinfunction "V_{CCIO}")
			(pintype "passive")
		)
		(pad "57" smd roundrect
			(at -0.25 -4.414 270)
			(size 0.2 0.875)
			(layers "F.Cu" "F.Mask" "F.Paste")
			(roundrect_rratio 0.25)
			(net 680 "unconnected-(U19-DDBUS5-Pad57)")
			(pinfunction "DDBUS5")
			(pintype "bidirectional+no_connect")
		)
		(pad "58" smd roundrect
			(at -0.75 -4.414 270)
			(size 0.2 0.875)
			(layers "F.Cu" "F.Mask" "F.Paste")
			(roundrect_rratio 0.25)
			(net 681 "unconnected-(U19-DDBUS6-Pad58)")
			(pinfunction "DDBUS6")
			(pintype "bidirectional+no_connect")
		)
		(pad "59" smd roundrect
			(at -1.25 -4.414 270)
			(size 0.2 0.875)
			(layers "F.Cu" "F.Mask" "F.Paste")
			(roundrect_rratio 0.25)
			(net 682 "unconnected-(U19-DDBUS7-Pad59)")
			(pinfunction "DDBUS7")
			(pintype "bidirectional+no_connect")
		)
		(pad "60" smd roundrect
			(at -1.75 -4.414 270)
			(size 0.2 0.875)
			(layers "F.Cu" "F.Mask" "F.Paste")
			(roundrect_rratio 0.25)
			(net 683 "unconnected-(U19-PWREN-Pad60)")
			(pinfunction "PWREN")
			(pintype "output+no_connect")
		)
		(pad "61" smd roundrect
			(at -2.25 -4.414 270)
			(size 0.2 0.875)
			(layers "F.Cu" "F.Mask" "F.Paste")
			(roundrect_rratio 0.25)
			(net 684 "unconnected-(U19-EEDATA-Pad61)")
			(pinfunction "EEDATA")
			(pintype "bidirectional+no_connect")
		)
		(pad "62" smd roundrect
			(at -2.75 -4.414 270)
			(size 0.2 0.875)
			(layers "F.Cu" "F.Mask" "F.Paste")
			(roundrect_rratio 0.25)
			(net 685 "unconnected-(U19-EECLK-Pad62)")
			(pinfunction "EECLK")
			(pintype "output+no_connect")
		)
		(pad "63" smd roundrect
			(at -3.25 -4.414 270)
			(size 0.2 0.875)
			(layers "F.Cu" "F.Mask" "F.Paste")
			(roundrect_rratio 0.25)
			(net 686 "unconnected-(U19-EECS-Pad63)")
			(pinfunction "EECS")
			(pintype "bidirectional+no_connect")
		)
		(pad "64" smd roundrect
			(at -3.75 -4.414 270)
			(size 0.2 0.875)
			(layers "F.Cu" "F.Mask" "F.Paste")
			(roundrect_rratio 0.25)
			(net 597 "1V8_FT")
			(pinfunction "V_{CORE}")
			(pintype "passive")
		)
		(pad "65" smd roundrect
			(at 0 0 270)
			(size 4.7 4.7)
			(layers "F.Cu" "F.Mask")
			(roundrect_rratio 0.053191)
			(net 1 "GND")
			(pinfunction "GND")
			(pintype "passive")
		)
	)
)
